(kicad_pcb
	(version 20260206)
	(generator "pcbnew")
	(generator_version "10.0")
	(general
		(thickness 1.6)
		(legacy_teardrops no)
	)
	(paper "A4")
	(title_block
		(title "01162023_DA0F0TEBIF0_F0T_Expander_BD_F_brd_V02_OCP.brd")
		(comment 1 "Grand Teton / footprints 371-376 of 9728")
	)
	(layers
		(0 "F.Cu" signal "TOP")
		(4 "In1.Cu" signal "GND")
		(6 "In2.Cu" signal "VCC")
		(8 "In3.Cu" signal "VCC1")
		(10 "In4.Cu" signal "GND1")
		(12 "In5.Cu" signal "IN1")
		(14 "In6.Cu" signal "GND2")
		(16 "In7.Cu" signal "IN2")
		(18 "In8.Cu" signal "GND3")
		(20 "In9.Cu" signal "IN3")
		(22 "In10.Cu" signal "GND4")
		(24 "In11.Cu" signal "IN4")
		(26 "In12.Cu" signal "GND5")
		(28 "In13.Cu" signal "IN5")
		(30 "In14.Cu" signal "GND6")
		(32 "In15.Cu" signal "IN6")
		(34 "In16.Cu" signal "GND7")
		(2 "B.Cu" signal "BOTTOM")
		(9 "F.Adhes" user "F.Adhesive")
		(11 "B.Adhes" user "B.Adhesive")
		(13 "F.Paste" user "Package Geometry/Pastemask Top")
		(15 "B.Paste" user "Package Geometry/Pastemask Bottom")
		(5 "F.SilkS" user "Ref Des/Silkscreen Top")
		(7 "B.SilkS" user "Ref Des/Silkscreen Bottom")
		(1 "F.Mask" user "Board Geometry/Soldermask Top")
		(3 "B.Mask" user "Board Geometry/Soldermask Bottom")
		(17 "Dwgs.User" user "User.Drawings")
		(19 "Cmts.User" user "User.Comments")
		(21 "Eco1.User" user "User.Eco1")
		(23 "Eco2.User" user "User.Eco2")
		(25 "Edge.Cuts" user "Board Geometry/Outline")
		(27 "Margin" user)
		(31 "F.CrtYd" user "Package Geometry/Place Bound Top")
		(29 "B.CrtYd" user "Package Geometry/Place Bound Bottom")
		(35 "F.Fab" user "Ref Des/Assembly Top")
		(33 "B.Fab" user "Ref Des/Assembly Bottom")
	)
	(footprint ""
		(layer "F.Cu")
		(at 206.117698 -304.036476 90)
		(property "Reference" "R1315"
			(at 0 0 90)
			(layer "F.SilkS")
			(hide yes)
			(effects
				(font
					(size 1.27 1.27)
				)
			)
		)
		(property "Value" ""
			(at 0 0 90)
			(layer "F.Fab")
			(effects
				(font
					(size 1.27 1.27)
				)
			)
		)
		(duplicate_pad_numbers_are_jumpers no)
		(fp_line
			(start 0.7874 -0.4064)
			(end 0.7874 0.4064)
			(stroke
				(width 0.1524)
				(type default)
			)
			(layer "F.SilkS")
		)
		(fp_line
			(start -0.7874 -0.4064)
			(end 0.7874 -0.4064)
			(stroke
				(width 0.1524)
				(type default)
			)
			(layer "F.SilkS")
		)
		(fp_line
			(start 0.7874 0.4064)
			(end -0.7874 0.4064)
			(stroke
				(width 0.1524)
				(type default)
			)
			(layer "F.SilkS")
		)
		(fp_line
			(start -0.7874 0.4064)
			(end -0.7874 -0.4064)
			(stroke
				(width 0.1524)
				(type default)
			)
			(layer "F.SilkS")
		)
		(fp_line
			(start -0.12065 -0.305054)
			(end -0.12065 -0.2794)
			(stroke
				(width 0.1)
				(type default)
			)
			(layer "F.Fab")
		)
		(fp_line
			(start -0.67945 -0.305054)
			(end -0.12065 -0.305054)
			(stroke
				(width 0.1)
				(type default)
			)
			(layer "F.Fab")
		)
		(fp_line
			(start 0.67945 -0.3048)
			(end 0.67945 0.3048)
			(stroke
				(width 0.1)
				(type default)
			)
			(layer "F.Fab")
		)
		(fp_line
			(start 0.12065 -0.3048)
			(end 0.67945 -0.3048)
			(stroke
				(width 0.1)
				(type default)
			)
			(layer "F.Fab")
		)
		(fp_line
			(start 0.12065 -0.2794)
			(end 0.12065 -0.3048)
			(stroke
				(width 0.1)
				(type default)
			)
			(layer "F.Fab")
		)
		(fp_line
			(start -0.12065 -0.2794)
			(end 0.12065 -0.2794)
			(stroke
				(width 0.1)
				(type default)
			)
			(layer "F.Fab")
		)
		(fp_line
			(start 0.120396 0.2794)
			(end -0.12065 0.2794)
			(stroke
				(width 0.1)
				(type default)
			)
			(layer "F.Fab")
		)
		(fp_line
			(start -0.12065 0.2794)
			(end -0.12065 0.3048)
			(stroke
				(width 0.1)
				(type default)
			)
			(layer "F.Fab")
		)
		(fp_line
			(start 0.67945 0.3048)
			(end 0.120396 0.3048)
			(stroke
				(width 0.1)
				(type default)
			)
			(layer "F.Fab")
		)
		(fp_line
			(start 0.120396 0.3048)
			(end 0.120396 0.2794)
			(stroke
				(width 0.1)
				(type default)
			)
			(layer "F.Fab")
		)
		(fp_line
			(start -0.12065 0.3048)
			(end -0.67945 0.3048)
			(stroke
				(width 0.1)
				(type default)
			)
			(layer "F.Fab")
		)
		(fp_line
			(start -0.67945 0.3048)
			(end -0.67945 -0.305054)
			(stroke
				(width 0.1)
				(type default)
			)
			(layer "F.Fab")
		)
		(pad "1" smd circle
			(at -0.40005 0 90)
			(size 0 0)
			(layers "F.Cu" "F.Mask" "F.Paste")
			(net "GND")
		)
		(pad "2" smd circle
			(at 0.40005 0 90)
			(size 0 0)
			(layers "F.Cu" "F.Mask" "F.Paste")
			(net "PEX1_SPARE3")
		)
	)
	(footprint ""
		(layer "F.Cu")
		(at 238.019336 -47.197264 180)
		(property "Reference" "PC549"
			(at 0 0 180)
			(layer "F.SilkS")
			(hide yes)
			(effects
				(font
					(size 1.27 1.27)
				)
			)
		)
		(property "Value" ""
			(at 0 0 180)
			(layer "F.Fab")
			(effects
				(font
					(size 1.27 1.27)
				)
			)
		)
		(duplicate_pad_numbers_are_jumpers no)
		(fp_line
			(start 1.524 0.762)
			(end -1.524 0.762)
			(stroke
				(width 0.1524)
				(type default)
			)
			(layer "F.SilkS")
		)
		(fp_line
			(start 1.524 -0.762)
			(end 1.524 0.762)
			(stroke
				(width 0.1524)
				(type default)
			)
			(layer "F.SilkS")
		)
		(fp_line
			(start -1.524 0.762)
			(end -1.524 -0.762)
			(stroke
				(width 0.1524)
				(type default)
			)
			(layer "F.SilkS")
		)
		(fp_line
			(start -1.524 -0.762)
			(end 1.524 -0.762)
			(stroke
				(width 0.1524)
				(type default)
			)
			(layer "F.SilkS")
		)
		(fp_line
			(start 1.1049 0.724916)
			(end 1.1049 -0.724916)
			(stroke
				(width 0.1)
				(type default)
			)
			(layer "F.Fab")
		)
		(fp_line
			(start 1.1049 -0.724916)
			(end -1.1049 -0.724916)
			(stroke
				(width 0.1)
				(type default)
			)
			(layer "F.Fab")
		)
		(fp_line
			(start -1.1049 0.724916)
			(end 1.1049 0.724916)
			(stroke
				(width 0.1)
				(type default)
			)
			(layer "F.Fab")
		)
		(fp_line
			(start -1.1049 -0.724916)
			(end -1.1049 0.724916)
			(stroke
				(width 0.1)
				(type default)
			)
			(layer "F.Fab")
		)
		(pad "1" smd rect
			(at -0.889 0)
			(size 1.016 1.27)
			(layers "F.Cu" "F.Mask" "F.Paste")
			(net "P3V3_SSD8")
		)
		(pad "2" smd rect
			(at 0.889 0)
			(size 1.016 1.27)
			(layers "F.Cu" "F.Mask" "F.Paste")
			(net "GND")
		)
	)
	(footprint ""
		(layer "F.Cu")
		(at 221.562422 -22.937216 90)
		(property "Reference" "R1684"
			(at 0 0 90)
			(layer "F.SilkS")
			(hide yes)
			(effects
				(font
					(size 1.27 1.27)
				)
			)
		)
		(property "Value" ""
			(at 0 0 90)
			(layer "F.Fab")
			(effects
				(font
					(size 1.27 1.27)
				)
			)
		)
		(duplicate_pad_numbers_are_jumpers no)
		(fp_line
			(start 0.7874 -0.4064)
			(end 0.7874 0.4064)
			(stroke
				(width 0.1524)
				(type default)
			)
			(layer "F.SilkS")
		)
		(fp_line
			(start -0.7874 -0.4064)
			(end 0.7874 -0.4064)
			(stroke
				(width 0.1524)
				(type default)
			)
			(layer "F.SilkS")
		)
		(fp_line
			(start 0.7874 0.4064)
			(end -0.7874 0.4064)
			(stroke
				(width 0.1524)
				(type default)
			)
			(layer "F.SilkS")
		)
		(fp_line
			(start -0.7874 0.4064)
			(end -0.7874 -0.4064)
			(stroke
				(width 0.1524)
				(type default)
			)
			(layer "F.SilkS")
		)
		(fp_line
			(start -0.12065 -0.305054)
			(end -0.12065 -0.2794)
			(stroke
				(width 0.1)
				(type default)
			)
			(layer "F.Fab")
		)
		(fp_line
			(start -0.67945 -0.305054)
			(end -0.12065 -0.305054)
			(stroke
				(width 0.1)
				(type default)
			)
			(layer "F.Fab")
		)
		(fp_line
			(start 0.67945 -0.3048)
			(end 0.67945 0.3048)
			(stroke
				(width 0.1)
				(type default)
			)
			(layer "F.Fab")
		)
		(fp_line
			(start 0.12065 -0.3048)
			(end 0.67945 -0.3048)
			(stroke
				(width 0.1)
				(type default)
			)
			(layer "F.Fab")
		)
		(fp_line
			(start 0.12065 -0.2794)
			(end 0.12065 -0.3048)
			(stroke
				(width 0.1)
				(type default)
			)
			(layer "F.Fab")
		)
		(fp_line
			(start -0.12065 -0.2794)
			(end 0.12065 -0.2794)
			(stroke
				(width 0.1)
				(type default)
			)
			(layer "F.Fab")
		)
		(fp_line
			(start 0.120396 0.2794)
			(end -0.12065 0.2794)
			(stroke
				(width 0.1)
				(type default)
			)
			(layer "F.Fab")
		)
		(fp_line
			(start -0.12065 0.2794)
			(end -0.12065 0.3048)
			(stroke
				(width 0.1)
				(type default)
			)
			(layer "F.Fab")
		)
		(fp_line
			(start 0.67945 0.3048)
			(end 0.120396 0.3048)
			(stroke
				(width 0.1)
				(type default)
			)
			(layer "F.Fab")
		)
		(fp_line
			(start 0.120396 0.3048)
			(end 0.120396 0.2794)
			(stroke
				(width 0.1)
				(type default)
			)
			(layer "F.Fab")
		)
		(fp_line
			(start -0.12065 0.3048)
			(end -0.67945 0.3048)
			(stroke
				(width 0.1)
				(type default)
			)
			(layer "F.Fab")
		)
		(fp_line
			(start -0.67945 0.3048)
			(end -0.67945 -0.305054)
			(stroke
				(width 0.1)
				(type default)
			)
			(layer "F.Fab")
		)
		(pad "1" smd circle
			(at -0.40005 0 90)
			(size 0 0)
			(layers "F.Cu" "F.Mask" "F.Paste")
			(net "SMB_BIC_I2C9_MUX0_SSD7_R_SDA")
		)
		(pad "2" smd circle
			(at 0.40005 0 90)
			(size 0 0)
			(layers "F.Cu" "F.Mask" "F.Paste")
			(net "SMB_ISO_SSD7_SDA")
		)
	)
	(footprint ""
		(layer "F.Cu")
		(at 269.204694 -140.85697 180)
		(property "Reference" "R237"
			(at 0 0 180)
			(layer "F.SilkS")
			(hide yes)
			(effects
				(font
					(size 1.27 1.27)
				)
			)
		)
		(property "Value" ""
			(at 0 0 180)
			(layer "F.Fab")
			(effects
				(font
					(size 1.27 1.27)
				)
			)
		)
		(duplicate_pad_numbers_are_jumpers no)
		(fp_line
			(start 0.7874 0.4064)
			(end -0.7874 0.4064)
			(stroke
				(width 0.1524)
				(type default)
			)
			(layer "F.SilkS")
		)
		(fp_line
			(start 0.7874 -0.4064)
			(end 0.7874 0.4064)
			(stroke
				(width 0.1524)
				(type default)
			)
			(layer "F.SilkS")
		)
		(fp_line
			(start -0.7874 0.4064)
			(end -0.7874 -0.4064)
			(stroke
				(width 0.1524)
				(type default)
			)
			(layer "F.SilkS")
		)
		(fp_line
			(start -0.7874 -0.4064)
			(end 0.7874 -0.4064)
			(stroke
				(width 0.1524)
				(type default)
			)
			(layer "F.SilkS")
		)
		(fp_line
			(start 0.67945 0.3048)
			(end 0.120396 0.3048)
			(stroke
				(width 0.1)
				(type default)
			)
			(layer "F.Fab")
		)
		(fp_line
			(start 0.67945 -0.3048)
			(end 0.67945 0.3048)
			(stroke
				(width 0.1)
				(type default)
			)
			(layer "F.Fab")
		)
		(fp_line
			(start 0.12065 -0.2794)
			(end 0.12065 -0.3048)
			(stroke
				(width 0.1)
				(type default)
			)
			(layer "F.Fab")
		)
		(fp_line
			(start 0.12065 -0.3048)
			(end 0.67945 -0.3048)
			(stroke
				(width 0.1)
				(type default)
			)
			(layer "F.Fab")
		)
		(fp_line
			(start 0.120396 0.3048)
			(end 0.120396 0.2794)
			(stroke
				(width 0.1)
				(type default)
			)
			(layer "F.Fab")
		)
		(fp_line
			(start 0.120396 0.2794)
			(end -0.12065 0.2794)
			(stroke
				(width 0.1)
				(type default)
			)
			(layer "F.Fab")
		)
		(fp_line
			(start -0.12065 0.3048)
			(end -0.67945 0.3048)
			(stroke
				(width 0.1)
				(type default)
			)
			(layer "F.Fab")
		)
		(fp_line
			(start -0.12065 0.2794)
			(end -0.12065 0.3048)
			(stroke
				(width 0.1)
				(type default)
			)
			(layer "F.Fab")
		)
		(fp_line
			(start -0.12065 -0.2794)
			(end 0.12065 -0.2794)
			(stroke
				(width 0.1)
				(type default)
			)
			(layer "F.Fab")
		)
		(fp_line
			(start -0.12065 -0.305054)
			(end -0.12065 -0.2794)
			(stroke
				(width 0.1)
				(type default)
			)
			(layer "F.Fab")
		)
		(fp_line
			(start -0.67945 0.3048)
			(end -0.67945 -0.305054)
			(stroke
				(width 0.1)
				(type default)
			)
			(layer "F.Fab")
		)
		(fp_line
			(start -0.67945 -0.305054)
			(end -0.12065 -0.305054)
			(stroke
				(width 0.1)
				(type default)
			)
			(layer "F.Fab")
		)
		(pad "1" smd circle
			(at -0.40005 0 180)
			(size 0 0)
			(layers "F.Cu" "F.Mask" "F.Paste")
			(net "NIC4_BIF2_N")
		)
		(pad "2" smd circle
			(at 0.40005 0 180)
			(size 0 0)
			(layers "F.Cu" "F.Mask" "F.Paste")
			(net "P3V3_AUX")
		)
	)
	(footprint ""
		(layer "F.Cu")
		(at 167.16248 -22.955504 -90)
		(property "Reference" "C2721"
			(at 0 0 270)
			(layer "F.SilkS")
			(hide yes)
			(effects
				(font
					(size 1.27 1.27)
				)
			)
		)
		(property "Value" ""
			(at 0 0 270)
			(layer "F.Fab")
			(effects
				(font
					(size 1.27 1.27)
				)
			)
		)
		(duplicate_pad_numbers_are_jumpers no)
		(fp_line
			(start -0.7874 0.4064)
			(end -0.7874 -0.4064)
			(stroke
				(width 0.1524)
				(type default)
			)
			(layer "F.SilkS")
		)
		(fp_line
			(start 0.7874 0.4064)
			(end -0.7874 0.4064)
			(stroke
				(width 0.1524)
				(type default)
			)
			(layer "F.SilkS")
		)
		(fp_line
			(start -0.7874 -0.4064)
			(end 0.7874 -0.4064)
			(stroke
				(width 0.1524)
				(type default)
			)
			(layer "F.SilkS")
		)
		(fp_line
			(start 0.7874 -0.4064)
			(end 0.7874 0.4064)
			(stroke
				(width 0.1524)
				(type default)
			)
			(layer "F.SilkS")
		)
		(fp_line
			(start -0.67945 0.3048)
			(end -0.67945 -0.305054)
			(stroke
				(width 0.1)
				(type default)
			)
			(layer "F.Fab")
		)
		(fp_line
			(start -0.12065 0.3048)
			(end -0.67945 0.3048)
			(stroke
				(width 0.1)
				(type default)
			)
			(layer "F.Fab")
		)
		(fp_line
			(start 0.120396 0.3048)
			(end 0.120396 0.2794)
			(stroke
				(width 0.1)
				(type default)
			)
			(layer "F.Fab")
		)
		(fp_line
			(start 0.67945 0.3048)
			(end 0.120396 0.3048)
			(stroke
				(width 0.1)
				(type default)
			)
			(layer "F.Fab")
		)
		(fp_line
			(start -0.12065 0.2794)
			(end -0.12065 0.3048)
			(stroke
				(width 0.1)
				(type default)
			)
			(layer "F.Fab")
		)
		(fp_line
			(start 0.120396 0.2794)
			(end -0.12065 0.2794)
			(stroke
				(width 0.1)
				(type default)
			)
			(layer "F.Fab")
		)
		(fp_line
			(start -0.12065 -0.2794)
			(end 0.12065 -0.2794)
			(stroke
				(width 0.1)
				(type default)
			)
			(layer "F.Fab")
		)
		(fp_line
			(start 0.12065 -0.2794)
			(end 0.12065 -0.3048)
			(stroke
				(width 0.1)
				(type default)
			)
			(layer "F.Fab")
		)
		(fp_line
			(start 0.12065 -0.3048)
			(end 0.67945 -0.3048)
			(stroke
				(width 0.1)
				(type default)
			)
			(layer "F.Fab")
		)
		(fp_line
			(start 0.67945 -0.3048)
			(end 0.67945 0.3048)
			(stroke
				(width 0.1)
				(type default)
			)
			(layer "F.Fab")
		)
		(fp_line
			(start -0.67945 -0.305054)
			(end -0.12065 -0.305054)
			(stroke
				(width 0.1)
				(type default)
			)
			(layer "F.Fab")
		)
		(fp_line
			(start -0.12065 -0.305054)
			(end -0.12065 -0.2794)
			(stroke
				(width 0.1)
				(type default)
			)
			(layer "F.Fab")
		)
		(pad "1" smd circle
			(at -0.40005 0 270)
			(size 0 0)
			(layers "F.Cu" "F.Mask" "F.Paste")
			(net "GND")
		)
		(pad "2" smd circle
			(at 0.40005 0 270)
			(size 0 0)
			(layers "F.Cu" "F.Mask" "F.Paste")
			(net "P3V3_AUX")
		)
	)
	(footprint ""
		(layer "F.Cu")
		(at 338.074 -141.859 180)
		(property "Reference" "R4837"
			(at 0 0 180)
			(layer "F.SilkS")
			(hide yes)
			(effects
				(font
					(size 1.27 1.27)
				)
			)
		)
		(property "Value" ""
			(at 0 0 180)
			(layer "F.Fab")
			(effects
				(font
					(size 1.27 1.27)
				)
			)
		)
		(duplicate_pad_numbers_are_jumpers no)
		(fp_line
			(start 0.7874 0.4064)
			(end -0.7874 0.4064)
			(stroke
				(width 0.1524)
				(type default)
			)
			(layer "F.SilkS")
		)
		(fp_line
			(start 0.7874 -0.4064)
			(end 0.7874 0.4064)
			(stroke
				(width 0.1524)
				(type default)
			)
			(layer "F.SilkS")
		)
		(fp_line
			(start -0.7874 0.4064)
			(end -0.7874 -0.4064)
			(stroke
				(width 0.1524)
				(type default)
			)
			(layer "F.SilkS")
		)
		(fp_line
			(start -0.7874 -0.4064)
			(end 0.7874 -0.4064)
			(stroke
				(width 0.1524)
				(type default)
			)
			(layer "F.SilkS")
		)
		(fp_line
			(start 0.67945 0.3048)
			(end 0.120396 0.3048)
			(stroke
				(width 0.1)
				(type default)
			)
			(layer "F.Fab")
		)
		(fp_line
			(start 0.67945 -0.3048)
			(end 0.67945 0.3048)
			(stroke
				(width 0.1)
				(type default)
			)
			(layer "F.Fab")
		)
		(fp_line
			(start 0.12065 -0.2794)
			(end 0.12065 -0.3048)
			(stroke
				(width 0.1)
				(type default)
			)
			(layer "F.Fab")
		)
		(fp_line
			(start 0.12065 -0.3048)
			(end 0.67945 -0.3048)
			(stroke
				(width 0.1)
				(type default)
			)
			(layer "F.Fab")
		)
		(fp_line
			(start 0.120396 0.3048)
			(end 0.120396 0.2794)
			(stroke
				(width 0.1)
				(type default)
			)
			(layer "F.Fab")
		)
		(fp_line
			(start 0.120396 0.2794)
			(end -0.12065 0.2794)
			(stroke
				(width 0.1)
				(type default)
			)
			(layer "F.Fab")
		)
		(fp_line
			(start -0.12065 0.3048)
			(end -0.67945 0.3048)
			(stroke
				(width 0.1)
				(type default)
			)
			(layer "F.Fab")
		)
		(fp_line
			(start -0.12065 0.2794)
			(end -0.12065 0.3048)
			(stroke
				(width 0.1)
				(type default)
			)
			(layer "F.Fab")
		)
		(fp_line
			(start -0.12065 -0.2794)
			(end 0.12065 -0.2794)
			(stroke
				(width 0.1)
				(type default)
			)
			(layer "F.Fab")
		)
		(fp_line
			(start -0.12065 -0.305054)
			(end -0.12065 -0.2794)
			(stroke
				(width 0.1)
				(type default)
			)
			(layer "F.Fab")
		)
		(fp_line
			(start -0.67945 0.3048)
			(end -0.67945 -0.305054)
			(stroke
				(width 0.1)
				(type default)
			)
			(layer "F.Fab")
		)
		(fp_line
			(start -0.67945 -0.305054)
			(end -0.12065 -0.305054)
			(stroke
				(width 0.1)
				(type default)
			)
			(layer "F.Fab")
		)
		(pad "1" smd circle
			(at -0.40005 0 180)
			(size 0 0)
			(layers "F.Cu" "F.Mask" "F.Paste")
			(net "RST_PEX_SSD15_PERST_N")
		)
		(pad "2" smd circle
			(at 0.40005 0 180)
			(size 0 0)
			(layers "F.Cu" "F.Mask" "F.Paste")
			(net "RST_PEX_SSD15_PERST_R_N")
		)
	)
)
